# S9S_MB_2U (Grand Teton) — schematic netlist excerpt (pin names and nets, part order shuffled) for the footprints in the layout excerpt that follows; sources: Cadence DE-HDL packaged netlist, KiCad conversion of 03242023_DA0F0TMBIJ0_F0T_Motherboard_J_brd_V01_OCP.brd

C1552  Q_CAP_DIFFBUS  DIFF BUS_0.22UF 6.3V 20% X6S  pkg C0201  page 175 : \1\ = P5E_CPU0_PE4_TX_C_DN<13> ; \2\ = P5E_CPU0_PE4_TX_DN<13>
PR522  Q_RES  100 1% CHIP  pkg 0402LF  page 274 : A = VSENSE_PVCCFA_EHV_CPU0_DP ; B = PVCCFA_EHV_CPU0
R1365  Q_RES  1K 1% CHIP  pkg 0402LF  page 134 : A = FM_JTAG_TCK_MUX_SEL ; B = GND

(kicad_pcb
	(version 20260206)
	(generator "pcbnew")
	(generator_version "10.0")
	(general
		(thickness 1.6)
		(legacy_teardrops no)
	)
	(paper "A4")
	(title_block
		(title "03242023_DA0F0TMBIJ0_F0T_Motherboard_J_brd_V01_OCP.brd")
		(comment 1 "Grand Teton / footprints 2300-2302 of 6105")
	)
	(layers
		(0 "F.Cu" signal "TOP")
		(4 "In1.Cu" signal "GND")
		(6 "In2.Cu" signal "IN1")
		(8 "In3.Cu" signal "GND1")
		(10 "In4.Cu" signal "IN2")
		(12 "In5.Cu" signal "GND2")
		(14 "In6.Cu" signal "IN3")
		(16 "In7.Cu" signal "GND3")
		(18 "In8.Cu" signal "VCC")
		(20 "In9.Cu" signal "VCC1")
		(22 "In10.Cu" signal "GND4")
		(24 "In11.Cu" signal "IN4")
		(26 "In12.Cu" signal "GND5")
		(28 "In13.Cu" signal "IN5")
		(30 "In14.Cu" signal "GND6")
		(32 "In15.Cu" signal "IN6")
		(34 "In16.Cu" signal "GND7")
		(2 "B.Cu" signal "BOTTOM")
		(9 "F.Adhes" user "F.Adhesive")
		(11 "B.Adhes" user "B.Adhesive")
		(13 "F.Paste" user "Package Geometry/Pastemask Top")
		(15 "B.Paste" user "Package Geometry/Pastemask Bottom")
		(5 "F.SilkS" user "Ref Des/Silkscreen Top")
		(7 "B.SilkS" user "Ref Des/Silkscreen Bottom")
		(1 "F.Mask" user "Board Geometry/Soldermask Top")
		(3 "B.Mask" user "Board Geometry/Soldermask Bottom")
		(17 "Dwgs.User" user "User.Drawings")
		(19 "Cmts.User" user "User.Comments")
		(21 "Eco1.User" user "User.Eco1")
		(23 "Eco2.User" user "User.Eco2")
		(25 "Edge.Cuts" user "Board Geometry/Outline")
		(27 "Margin" user)
		(31 "F.CrtYd" user "Package Geometry/Place Bound Top")
		(29 "B.CrtYd" user "Package Geometry/Place Bound Bottom")
		(35 "F.Fab" user "Ref Des/Assembly Top")
		(33 "B.Fab" user "Ref Des/Assembly Bottom")
	)
	(footprint ""
		(layer "F.Cu")
		(at 398.270476 -148.010118 90)
		(property "Reference" "PR522"
			(at 0 0 90)
			(layer "F.SilkS")
			(hide yes)
			(effects
				(font
					(size 1.27 1.27)
				)
			)
		)
		(property "Value" ""
			(at 0 0 90)
			(layer "F.Fab")
			(effects
				(font
					(size 1.27 1.27)
				)
			)
		)
		(duplicate_pad_numbers_are_jumpers no)
		(fp_line
			(start 0.7874 -0.4064)
			(end 0.7874 0.4064)
			(stroke
				(width 0.1524)
				(type default)
			)
			(layer "F.SilkS")
		)
		(fp_line
			(start -0.7874 -0.4064)
			(end 0.7874 -0.4064)
			(stroke
				(width 0.1524)
				(type default)
			)
			(layer "F.SilkS")
		)
		(fp_line
			(start 0.7874 0.4064)
			(end -0.7874 0.4064)
			(stroke
				(width 0.1524)
				(type default)
			)
			(layer "F.SilkS")
		)
		(fp_line
			(start -0.7874 0.4064)
			(end -0.7874 -0.4064)
			(stroke
				(width 0.1524)
				(type default)
			)
			(layer "F.SilkS")
		)
		(fp_line
			(start -0.12065 -0.305054)
			(end -0.12065 -0.2794)
			(stroke
				(width 0.1)
				(type default)
			)
			(layer "F.Fab")
		)
		(fp_line
			(start -0.67945 -0.305054)
			(end -0.12065 -0.305054)
			(stroke
				(width 0.1)
				(type default)
			)
			(layer "F.Fab")
		)
		(fp_line
			(start 0.67945 -0.3048)
			(end 0.67945 0.3048)
			(stroke
				(width 0.1)
				(type default)
			)
			(layer "F.Fab")
		)
		(fp_line
			(start 0.12065 -0.3048)
			(end 0.67945 -0.3048)
			(stroke
				(width 0.1)
				(type default)
			)
			(layer "F.Fab")
		)
		(fp_line
			(start 0.12065 -0.2794)
			(end 0.12065 -0.3048)
			(stroke
				(width 0.1)
				(type default)
			)
			(layer "F.Fab")
		)
		(fp_line
			(start -0.12065 -0.2794)
			(end 0.12065 -0.2794)
			(stroke
				(width 0.1)
				(type default)
			)
			(layer "F.Fab")
		)
		(fp_line
			(start 0.120396 0.2794)
			(end -0.12065 0.2794)
			(stroke
				(width 0.1)
				(type default)
			)
			(layer "F.Fab")
		)
		(fp_line
			(start -0.12065 0.2794)
			(end -0.12065 0.3048)
			(stroke
				(width 0.1)
				(type default)
			)
			(layer "F.Fab")
		)
		(fp_line
			(start 0.67945 0.3048)
			(end 0.120396 0.3048)
			(stroke
				(width 0.1)
				(type default)
			)
			(layer "F.Fab")
		)
		(fp_line
			(start 0.120396 0.3048)
			(end 0.120396 0.2794)
			(stroke
				(width 0.1)
				(type default)
			)
			(layer "F.Fab")
		)
		(fp_line
			(start -0.12065 0.3048)
			(end -0.67945 0.3048)
			(stroke
				(width 0.1)
				(type default)
			)
			(layer "F.Fab")
		)
		(fp_line
			(start -0.67945 0.3048)
			(end -0.67945 -0.305054)
			(stroke
				(width 0.1)
				(type default)
			)
			(layer "F.Fab")
		)
		(pad "1" smd circle
			(at -0.40005 0 90)
			(size 0 0)
			(layers "F.Cu" "F.Mask" "F.Paste")
			(net "VSENSE_PVCCFA_EHV_CPU0_DP")
		)
		(pad "2" smd circle
			(at 0.40005 0 90)
			(size 0 0)
			(layers "F.Cu" "F.Mask" "F.Paste")
			(net "PVCCFA_EHV_CPU0")
		)
	)
	(footprint ""
		(layer "F.Cu")
		(at 108.05668 -61.102748)
		(property "Reference" "R1365"
			(at 0 0 0)
			(layer "F.SilkS")
			(hide yes)
			(effects
				(font
					(size 1.27 1.27)
				)
			)
		)
		(property "Value" ""
			(at 0 0 0)
			(layer "F.Fab")
			(effects
				(font
					(size 1.27 1.27)
				)
			)
		)
		(duplicate_pad_numbers_are_jumpers no)
		(fp_line
			(start -0.7874 -0.4064)
			(end 0.7874 -0.4064)
			(stroke
				(width 0.1524)
				(type default)
			)
			(layer "F.SilkS")
		)
		(fp_line
			(start -0.7874 0.4064)
			(end -0.7874 -0.4064)
			(stroke
				(width 0.1524)
				(type default)
			)
			(layer "F.SilkS")
		)
		(fp_line
			(start 0.7874 -0.4064)
			(end 0.7874 0.4064)
			(stroke
				(width 0.1524)
				(type default)
			)
			(layer "F.SilkS")
		)
		(fp_line
			(start 0.7874 0.4064)
			(end -0.7874 0.4064)
			(stroke
				(width 0.1524)
				(type default)
			)
			(layer "F.SilkS")
		)
		(fp_line
			(start -0.67945 -0.305054)
			(end -0.12065 -0.305054)
			(stroke
				(width 0.1)
				(type default)
			)
			(layer "F.Fab")
		)
		(fp_line
			(start -0.67945 0.3048)
			(end -0.67945 -0.305054)
			(stroke
				(width 0.1)
				(type default)
			)
			(layer "F.Fab")
		)
		(fp_line
			(start -0.12065 -0.305054)
			(end -0.12065 -0.2794)
			(stroke
				(width 0.1)
				(type default)
			)
			(layer "F.Fab")
		)
		(fp_line
			(start -0.12065 -0.2794)
			(end 0.12065 -0.2794)
			(stroke
				(width 0.1)
				(type default)
			)
			(layer "F.Fab")
		)
		(fp_line
			(start -0.12065 0.2794)
			(end -0.12065 0.3048)
			(stroke
				(width 0.1)
				(type default)
			)
			(layer "F.Fab")
		)
		(fp_line
			(start -0.12065 0.3048)
			(end -0.67945 0.3048)
			(stroke
				(width 0.1)
				(type default)
			)
			(layer "F.Fab")
		)
		(fp_line
			(start 0.120396 0.2794)
			(end -0.12065 0.2794)
			(stroke
				(width 0.1)
				(type default)
			)
			(layer "F.Fab")
		)
		(fp_line
			(start 0.120396 0.3048)
			(end 0.120396 0.2794)
			(stroke
				(width 0.1)
				(type default)
			)
			(layer "F.Fab")
		)
		(fp_line
			(start 0.12065 -0.3048)
			(end 0.67945 -0.3048)
			(stroke
				(width 0.1)
				(type default)
			)
			(layer "F.Fab")
		)
		(fp_line
			(start 0.12065 -0.2794)
			(end 0.12065 -0.3048)
			(stroke
				(width 0.1)
				(type default)
			)
			(layer "F.Fab")
		)
		(fp_line
			(start 0.67945 -0.3048)
			(end 0.67945 0.3048)
			(stroke
				(width 0.1)
				(type default)
			)
			(layer "F.Fab")
		)
		(fp_line
			(start 0.67945 0.3048)
			(end 0.120396 0.3048)
			(stroke
				(width 0.1)
				(type default)
			)
			(layer "F.Fab")
		)
		(pad "1" smd circle
			(at -0.40005 0)
			(size 0 0)
			(layers "F.Cu" "F.Mask" "F.Paste")
			(net "FM_JTAG_TCK_MUX_SEL")
		)
		(pad "2" smd circle
			(at 0.40005 0)
			(size 0 0)
			(layers "F.Cu" "F.Mask" "F.Paste")
			(net "GND")
		)
	)
	(footprint ""
		(layer "F.Cu")
		(at 343.776808 -402.371052 -90)
		(property "Reference" "C1552"
			(at 0 0 270)
			(layer "F.SilkS")
			(hide yes)
			(effects
				(font
					(size 1.27 1.27)
				)
			)
		)
		(property "Value" ""
			(at 0 0 270)
			(layer "F.Fab")
			(effects
				(font
					(size 1.27 1.27)
				)
			)
		)
		(duplicate_pad_numbers_are_jumpers no)
		(fp_line
			(start -0.299974 0.150114)
			(end -0.299974 -0.150114)
			(stroke
				(width 0.1)
				(type default)
			)
			(layer "F.Fab")
		)
		(fp_line
			(start 0.299974 0.150114)
			(end -0.299974 0.150114)
			(stroke
				(width 0.1)
				(type default)
			)
			(layer "F.Fab")
		)
		(fp_line
			(start -0.299974 -0.150114)
			(end 0.299974 -0.150114)
			(stroke
				(width 0.1)
				(type default)
			)
			(layer "F.Fab")
		)
		(fp_line
			(start 0.299974 -0.150114)
			(end 0.299974 0.150114)
			(stroke
				(width 0.1)
				(type default)
			)
			(layer "F.Fab")
		)
		(pad "1" smd rect
			(at -0.2667 0 270)
			(size 0.3048 0.381)
			(layers "F.Cu" "F.Mask" "F.Paste")
			(net "P5E_CPU0_PE4_TX_C_DN<13>")
		)
		(pad "2" smd rect
			(at 0.2667 0 270)
			(size 0.3048 0.381)
			(layers "F.Cu" "F.Mask" "F.Paste")
			(net "P5E_CPU0_PE4_TX_DN<13>")
		)
	)
)
